FILE_TYPE = MULTI_PHYS_TABLE;

PART 'MPQ8626GDZ'

{========================================================================================}
:VALUE         | PART_TYPE | MATERIAL | PART_NUMBER    = STANDARD    | LIFECYCLE     | PART_NUMBER   | JEDEC_TYPE        | DESCRIPTION                    | MANUFTR | MANUF_PN      | RD_CMPLS_LVL | CMPLS_LVL | FROM_PJ    | CLASS | DIP_SMD | DATA                  | EE_CHECK_LIST | FP_ECN | PSL | CREATOR | STATUS | MSD  | ESD_CDM | ESD_HBM | ESD_MM | PIN_LENGTH_SHORT_PIN | PIN_LENGTH_LONG_PIN | CREATEDAY  ;
{========================================================================================}
 'MPQ8626GD-Z' | 'SMLF'    | 'IC'     | 'AL008626000'(!) = ''               | ''               | 'AL008626000' |'QFN14_0-5_3X2XA'| 'IC CTRL(14P)MPQ8626GD-Z(QFN)' | 'MPS'   | 'MPQ8626GD-Z' | 'EP(V1)'     | ''        | 'F09A-BEN' | 'IC'  | ''      | 'MPS_MPQ8626GD-Z.pdf' | ''            | ''     | ''  | ''      | ''     | 'NA' | 'NA'    | 'NA'    | 'NA'   | '0 MILS'             | '0 MILS'            | '20171225'
 'MPQ8626GD-Z' | 'SMLF'    | 'EMPTY'  | 'AL008626000'(!) = ''               | ''               | 'AL008626000' |'QFN14_0-5_3X2XA'| 'IC CTRL(14P)MPQ8626GD-Z(QFN)' | 'MPS'   | 'MPQ8626GD-Z' | 'EP(V1)'     | ''        | 'F09A-BEN' | 'IC'  | ''      | 'MPS_MPQ8626GD-Z.pdf' | ''            | ''     | ''  | ''      | ''     | 'NA' | 'NA'    | 'NA'    | 'NA'   | '0 MILS'             | '0 MILS'            | '20171225'

END_PART

END.

